# S9S_MB_2U (Grand Teton) — schematic netlist excerpt (pin names and nets, part order shuffled) for the footprints in the layout excerpt that follows; sources: Cadence DE-HDL packaged netlist, KiCad conversion of 03242023_DA0F0TMBIJ0_F0T_Motherboard_J_brd_V01_OCP.brd

C2027  Q_CAP  0.1UF 25V 10% X7R  pkg 0402  page 171 : A = VSENSE_P3V3_INA230_1_INP ; B = VSENSE_P3V3_INA230_1_INN
R2738  Q_RES  33.2 1% CHIP  pkg 0402LF  page 223 : A = RST_PERST_SWB_N ; B = RST_PERST_SWB_R_N

(kicad_pcb
	(version 20260206)
	(generator "pcbnew")
	(generator_version "10.0")
	(general
		(thickness 1.6)
		(legacy_teardrops no)
	)
	(paper "A4")
	(title_block
		(title "03242023_DA0F0TMBIJ0_F0T_Motherboard_J_brd_V01_OCP.brd")
		(comment 1 "Grand Teton / footprints 3487-3488 of 6105")
	)
	(layers
		(0 "F.Cu" signal "TOP")
		(4 "In1.Cu" signal "GND")
		(6 "In2.Cu" signal "IN1")
		(8 "In3.Cu" signal "GND1")
		(10 "In4.Cu" signal "IN2")
		(12 "In5.Cu" signal "GND2")
		(14 "In6.Cu" signal "IN3")
		(16 "In7.Cu" signal "GND3")
		(18 "In8.Cu" signal "VCC")
		(20 "In9.Cu" signal "VCC1")
		(22 "In10.Cu" signal "GND4")
		(24 "In11.Cu" signal "IN4")
		(26 "In12.Cu" signal "GND5")
		(28 "In13.Cu" signal "IN5")
		(30 "In14.Cu" signal "GND6")
		(32 "In15.Cu" signal "IN6")
		(34 "In16.Cu" signal "GND7")
		(2 "B.Cu" signal "BOTTOM")
		(9 "F.Adhes" user "F.Adhesive")
		(11 "B.Adhes" user "B.Adhesive")
		(13 "F.Paste" user "Package Geometry/Pastemask Top")
		(15 "B.Paste" user "Package Geometry/Pastemask Bottom")
		(5 "F.SilkS" user "Ref Des/Silkscreen Top")
		(7 "B.SilkS" user "Ref Des/Silkscreen Bottom")
		(1 "F.Mask" user "Board Geometry/Soldermask Top")
		(3 "B.Mask" user "Board Geometry/Soldermask Bottom")
		(17 "Dwgs.User" user "User.Drawings")
		(19 "Cmts.User" user "User.Comments")
		(21 "Eco1.User" user "User.Eco1")
		(23 "Eco2.User" user "User.Eco2")
		(25 "Edge.Cuts" user "Board Geometry/Outline")
		(27 "Margin" user)
		(31 "F.CrtYd" user "Package Geometry/Place Bound Top")
		(29 "B.CrtYd" user "Package Geometry/Place Bound Bottom")
		(35 "F.Fab" user "Ref Des/Assembly Top")
		(33 "B.Fab" user "Ref Des/Assembly Bottom")
	)
	(footprint ""
		(layer "F.Cu")
		(at 22.92223 -427.500034)
		(property "Reference" "R2738"
			(at 0 0 0)
			(layer "F.SilkS")
			(hide yes)
			(effects
				(font
					(size 1.27 1.27)
				)
			)
		)
		(property "Value" ""
			(at 0 0 0)
			(layer "F.Fab")
			(effects
				(font
					(size 1.27 1.27)
				)
			)
		)
		(duplicate_pad_numbers_are_jumpers no)
		(fp_line
			(start -0.7874 -0.4064)
			(end 0.7874 -0.4064)
			(stroke
				(width 0.1524)
				(type default)
			)
			(layer "F.SilkS")
		)
		(fp_line
			(start -0.7874 0.4064)
			(end -0.7874 -0.4064)
			(stroke
				(width 0.1524)
				(type default)
			)
			(layer "F.SilkS")
		)
		(fp_line
			(start 0.7874 -0.4064)
			(end 0.7874 0.4064)
			(stroke
				(width 0.1524)
				(type default)
			)
			(layer "F.SilkS")
		)
		(fp_line
			(start 0.7874 0.4064)
			(end -0.7874 0.4064)
			(stroke
				(width 0.1524)
				(type default)
			)
			(layer "F.SilkS")
		)
		(fp_line
			(start -0.67945 -0.305054)
			(end -0.12065 -0.305054)
			(stroke
				(width 0.1)
				(type default)
			)
			(layer "F.Fab")
		)
		(fp_line
			(start -0.67945 0.3048)
			(end -0.67945 -0.305054)
			(stroke
				(width 0.1)
				(type default)
			)
			(layer "F.Fab")
		)
		(fp_line
			(start -0.12065 -0.305054)
			(end -0.12065 -0.2794)
			(stroke
				(width 0.1)
				(type default)
			)
			(layer "F.Fab")
		)
		(fp_line
			(start -0.12065 -0.2794)
			(end 0.12065 -0.2794)
			(stroke
				(width 0.1)
				(type default)
			)
			(layer "F.Fab")
		)
		(fp_line
			(start -0.12065 0.2794)
			(end -0.12065 0.3048)
			(stroke
				(width 0.1)
				(type default)
			)
			(layer "F.Fab")
		)
		(fp_line
			(start -0.12065 0.3048)
			(end -0.67945 0.3048)
			(stroke
				(width 0.1)
				(type default)
			)
			(layer "F.Fab")
		)
		(fp_line
			(start 0.120396 0.2794)
			(end -0.12065 0.2794)
			(stroke
				(width 0.1)
				(type default)
			)
			(layer "F.Fab")
		)
		(fp_line
			(start 0.120396 0.3048)
			(end 0.120396 0.2794)
			(stroke
				(width 0.1)
				(type default)
			)
			(layer "F.Fab")
		)
		(fp_line
			(start 0.12065 -0.3048)
			(end 0.67945 -0.3048)
			(stroke
				(width 0.1)
				(type default)
			)
			(layer "F.Fab")
		)
		(fp_line
			(start 0.12065 -0.2794)
			(end 0.12065 -0.3048)
			(stroke
				(width 0.1)
				(type default)
			)
			(layer "F.Fab")
		)
		(fp_line
			(start 0.67945 -0.3048)
			(end 0.67945 0.3048)
			(stroke
				(width 0.1)
				(type default)
			)
			(layer "F.Fab")
		)
		(fp_line
			(start 0.67945 0.3048)
			(end 0.120396 0.3048)
			(stroke
				(width 0.1)
				(type default)
			)
			(layer "F.Fab")
		)
		(pad "1" smd circle
			(at -0.40005 0)
			(size 0 0)
			(layers "F.Cu" "F.Mask" "F.Paste")
			(net "RST_PERST_SWB_N")
		)
		(pad "2" smd circle
			(at 0.40005 0)
			(size 0 0)
			(layers "F.Cu" "F.Mask" "F.Paste")
			(net "RST_PERST_SWB_R_N")
		)
	)
	(footprint ""
		(layer "F.Cu")
		(at 435.91226 -92.700348)
		(property "Reference" "C2027"
			(at 0 0 0)
			(layer "F.SilkS")
			(hide yes)
			(effects
				(font
					(size 1.27 1.27)
				)
			)
		)
		(property "Value" ""
			(at 0 0 0)
			(layer "F.Fab")
			(effects
				(font
					(size 1.27 1.27)
				)
			)
		)
		(duplicate_pad_numbers_are_jumpers no)
		(fp_line
			(start -0.7874 -0.4064)
			(end 0.7874 -0.4064)
			(stroke
				(width 0.1524)
				(type default)
			)
			(layer "F.SilkS")
		)
		(fp_line
			(start -0.7874 0.4064)
			(end -0.7874 -0.4064)
			(stroke
				(width 0.1524)
				(type default)
			)
			(layer "F.SilkS")
		)
		(fp_line
			(start 0.7874 -0.4064)
			(end 0.7874 0.4064)
			(stroke
				(width 0.1524)
				(type default)
			)
			(layer "F.SilkS")
		)
		(fp_line
			(start 0.7874 0.4064)
			(end -0.7874 0.4064)
			(stroke
				(width 0.1524)
				(type default)
			)
			(layer "F.SilkS")
		)
		(fp_line
			(start -0.67945 -0.305054)
			(end -0.12065 -0.305054)
			(stroke
				(width 0.1)
				(type default)
			)
			(layer "F.Fab")
		)
		(fp_line
			(start -0.67945 0.3048)
			(end -0.67945 -0.305054)
			(stroke
				(width 0.1)
				(type default)
			)
			(layer "F.Fab")
		)
		(fp_line
			(start -0.12065 -0.305054)
			(end -0.12065 -0.2794)
			(stroke
				(width 0.1)
				(type default)
			)
			(layer "F.Fab")
		)
		(fp_line
			(start -0.12065 -0.2794)
			(end 0.12065 -0.2794)
			(stroke
				(width 0.1)
				(type default)
			)
			(layer "F.Fab")
		)
		(fp_line
			(start -0.12065 0.2794)
			(end -0.12065 0.3048)
			(stroke
				(width 0.1)
				(type default)
			)
			(layer "F.Fab")
		)
		(fp_line
			(start -0.12065 0.3048)
			(end -0.67945 0.3048)
			(stroke
				(width 0.1)
				(type default)
			)
			(layer "F.Fab")
		)
		(fp_line
			(start 0.120396 0.2794)
			(end -0.12065 0.2794)
			(stroke
				(width 0.1)
				(type default)
			)
			(layer "F.Fab")
		)
		(fp_line
			(start 0.120396 0.3048)
			(end 0.120396 0.2794)
			(stroke
				(width 0.1)
				(type default)
			)
			(layer "F.Fab")
		)
		(fp_line
			(start 0.12065 -0.3048)
			(end 0.67945 -0.3048)
			(stroke
				(width 0.1)
				(type default)
			)
			(layer "F.Fab")
		)
		(fp_line
			(start 0.12065 -0.2794)
			(end 0.12065 -0.3048)
			(stroke
				(width 0.1)
				(type default)
			)
			(layer "F.Fab")
		)
		(fp_line
			(start 0.67945 -0.3048)
			(end 0.67945 0.3048)
			(stroke
				(width 0.1)
				(type default)
			)
			(layer "F.Fab")
		)
		(fp_line
			(start 0.67945 0.3048)
			(end 0.120396 0.3048)
			(stroke
				(width 0.1)
				(type default)
			)
			(layer "F.Fab")
		)
		(pad "1" smd circle
			(at -0.40005 0)
			(size 0 0)
			(layers "F.Cu" "F.Mask" "F.Paste")
			(net "VSENSE_P3V3_INA230_1_INP")
		)
		(pad "2" smd circle
			(at 0.40005 0)
			(size 0 0)
			(layers "F.Cu" "F.Mask" "F.Paste")
			(net "VSENSE_P3V3_INA230_1_INN")
		)
	)
)
